(kicad_pcb
	(version 20260206)
	(generator "pcbnew")
	(generator_version "10.0")
	(general
		(thickness 1.6)
		(legacy_teardrops no)
	)
	(paper "A4")
	(title_block
		(title "01162023_DA0F0TEBIF0_F0T_Expander_BD_F_brd_V02_OCP.brd")
		(comment 1 "Grand Teton / footprints 1195-1199 of 9728")
	)
	(layers
		(0 "F.Cu" signal "TOP")
		(4 "In1.Cu" signal "GND")
		(6 "In2.Cu" signal "VCC")
		(8 "In3.Cu" signal "VCC1")
		(10 "In4.Cu" signal "GND1")
		(12 "In5.Cu" signal "IN1")
		(14 "In6.Cu" signal "GND2")
		(16 "In7.Cu" signal "IN2")
		(18 "In8.Cu" signal "GND3")
		(20 "In9.Cu" signal "IN3")
		(22 "In10.Cu" signal "GND4")
		(24 "In11.Cu" signal "IN4")
		(26 "In12.Cu" signal "GND5")
		(28 "In13.Cu" signal "IN5")
		(30 "In14.Cu" signal "GND6")
		(32 "In15.Cu" signal "IN6")
		(34 "In16.Cu" signal "GND7")
		(2 "B.Cu" signal "BOTTOM")
		(9 "F.Adhes" user "F.Adhesive")
		(11 "B.Adhes" user "B.Adhesive")
		(13 "F.Paste" user "Package Geometry/Pastemask Top")
		(15 "B.Paste" user "Package Geometry/Pastemask Bottom")
		(5 "F.SilkS" user "Ref Des/Silkscreen Top")
		(7 "B.SilkS" user "Ref Des/Silkscreen Bottom")
		(1 "F.Mask" user "Board Geometry/Soldermask Top")
		(3 "B.Mask" user "Board Geometry/Soldermask Bottom")
		(17 "Dwgs.User" user "User.Drawings")
		(19 "Cmts.User" user "User.Comments")
		(21 "Eco1.User" user "User.Eco1")
		(23 "Eco2.User" user "User.Eco2")
		(25 "Edge.Cuts" user "Board Geometry/Outline")
		(27 "Margin" user)
		(31 "F.CrtYd" user "Package Geometry/Place Bound Top")
		(29 "B.CrtYd" user "Package Geometry/Place Bound Bottom")
		(35 "F.Fab" user "Ref Des/Assembly Top")
		(33 "B.Fab" user "Ref Des/Assembly Bottom")
	)
	(footprint ""
		(layer "F.Cu")
		(at 121.689622 -63.56223)
		(property "Reference" "Q200"
			(at 2.617978 -1.8161 0)
			(unlocked yes)
			(layer "F.SilkS")
			(effects
				(font
					(size 0.7874 0.5842)
					(thickness 0.1524)
				)
			)
		)
		(property "Value" ""
			(at 0 0 0)
			(layer "F.Fab")
			(effects
				(font
					(size 1.27 1.27)
				)
			)
		)
		(duplicate_pad_numbers_are_jumpers no)
		(fp_line
			(start -1.376172 -1.199896)
			(end -0.508 -1.199896)
			(stroke
				(width 0.1524)
				(type default)
			)
			(layer "F.SilkS")
		)
		(fp_line
			(start -1.376172 1.199896)
			(end -1.376172 -1.199896)
			(stroke
				(width 0.1524)
				(type default)
			)
			(layer "F.SilkS")
		)
		(fp_line
			(start -0.508 -1.199896)
			(end 0 -0.762)
			(stroke
				(width 0.1524)
				(type default)
			)
			(layer "F.SilkS")
		)
		(fp_line
			(start 0 -0.762)
			(end 0.508 -1.199896)
			(stroke
				(width 0.1524)
				(type default)
			)
			(layer "F.SilkS")
		)
		(fp_line
			(start 0.508 -1.199896)
			(end 1.376172 -1.199896)
			(stroke
				(width 0.1524)
				(type default)
			)
			(layer "F.SilkS")
		)
		(fp_line
			(start 1.376172 -1.199896)
			(end 1.376172 1.199896)
			(stroke
				(width 0.1524)
				(type default)
			)
			(layer "F.SilkS")
		)
		(fp_line
			(start 1.376172 1.199896)
			(end -1.376172 1.199896)
			(stroke
				(width 0.1524)
				(type default)
			)
			(layer "F.SilkS")
		)
		(fp_poly
			(pts
				(xy -0.47117 -1.199896) (xy 0.337058 -1.469136) (xy -0.20193 -2.008124)
			)
			(stroke
				(width 0)
				(type default)
			)
			(fill yes)
			(layer "F.SilkS")
		)
		(fp_line
			(start -0.674878 -1.100074)
			(end 0.674878 -1.100074)
			(stroke
				(width 0.1)
				(type default)
			)
			(layer "F.Fab")
		)
		(fp_line
			(start -0.674878 1.100074)
			(end -0.674878 -1.100074)
			(stroke
				(width 0.1)
				(type default)
			)
			(layer "F.Fab")
		)
		(fp_line
			(start 0.674878 -1.100074)
			(end 0.674878 1.100074)
			(stroke
				(width 0.1)
				(type default)
			)
			(layer "F.Fab")
		)
		(fp_line
			(start 0.674878 1.100074)
			(end -0.674878 1.100074)
			(stroke
				(width 0.1)
				(type default)
			)
			(layer "F.Fab")
		)
		(fp_poly
			(pts
				(xy -1.4605 -0.7493) (xy -2.2225 -1.1303) (xy -2.2225 -0.3683)
			)
			(stroke
				(width 0)
				(type default)
			)
			(fill yes)
			(layer "F.Fab")
		)
		(pad "1" smd rect
			(at -0.899922 -0.750062 270)
			(size 0.6096 0.6096)
			(layers "F.Cu" "F.Mask" "F.Paste")
			(net "GND")
		)
		(pad "2" smd rect
			(at -0.899922 0 270)
			(size 0.4064 0.6096)
			(layers "F.Cu" "F.Mask" "F.Paste")
			(net "P12V_SSD4_PG_G1")
		)
		(pad "3" smd rect
			(at -0.899922 0.750062 270)
			(size 0.6096 0.6096)
			(layers "F.Cu" "F.Mask" "F.Paste")
			(net "PWRGD_P12V_SSD4_D")
		)
		(pad "4" smd rect
			(at 0.899922 0.750062 270)
			(size 0.6096 0.6096)
			(layers "F.Cu" "F.Mask" "F.Paste")
			(net "GND")
		)
		(pad "5" smd rect
			(at 0.899922 0 270)
			(size 0.4064 0.6096)
			(layers "F.Cu" "F.Mask" "F.Paste")
			(net "P12V_SSD4_PG_G2")
		)
		(pad "6" smd rect
			(at 0.899922 -0.750062 270)
			(size 0.6096 0.6096)
			(layers "F.Cu" "F.Mask" "F.Paste")
			(net "P12V_SSD4_PG_G2")
		)
	)
	(footprint ""
		(layer "F.Cu")
		(at 95.105728 -243.792248 180)
		(property "Reference" "R816"
			(at 0 0 180)
			(layer "F.SilkS")
			(hide yes)
			(effects
				(font
					(size 1.27 1.27)
				)
			)
		)
		(property "Value" ""
			(at 0 0 180)
			(layer "F.Fab")
			(effects
				(font
					(size 1.27 1.27)
				)
			)
		)
		(duplicate_pad_numbers_are_jumpers no)
		(fp_line
			(start 0.7874 0.4064)
			(end -0.7874 0.4064)
			(stroke
				(width 0.1524)
				(type default)
			)
			(layer "F.SilkS")
		)
		(fp_line
			(start 0.7874 -0.4064)
			(end 0.7874 0.4064)
			(stroke
				(width 0.1524)
				(type default)
			)
			(layer "F.SilkS")
		)
		(fp_line
			(start -0.7874 0.4064)
			(end -0.7874 -0.4064)
			(stroke
				(width 0.1524)
				(type default)
			)
			(layer "F.SilkS")
		)
		(fp_line
			(start -0.7874 -0.4064)
			(end 0.7874 -0.4064)
			(stroke
				(width 0.1524)
				(type default)
			)
			(layer "F.SilkS")
		)
		(fp_line
			(start 0.67945 0.3048)
			(end 0.120396 0.3048)
			(stroke
				(width 0.1)
				(type default)
			)
			(layer "F.Fab")
		)
		(fp_line
			(start 0.67945 -0.3048)
			(end 0.67945 0.3048)
			(stroke
				(width 0.1)
				(type default)
			)
			(layer "F.Fab")
		)
		(fp_line
			(start 0.12065 -0.2794)
			(end 0.12065 -0.3048)
			(stroke
				(width 0.1)
				(type default)
			)
			(layer "F.Fab")
		)
		(fp_line
			(start 0.12065 -0.3048)
			(end 0.67945 -0.3048)
			(stroke
				(width 0.1)
				(type default)
			)
			(layer "F.Fab")
		)
		(fp_line
			(start 0.120396 0.3048)
			(end 0.120396 0.2794)
			(stroke
				(width 0.1)
				(type default)
			)
			(layer "F.Fab")
		)
		(fp_line
			(start 0.120396 0.2794)
			(end -0.12065 0.2794)
			(stroke
				(width 0.1)
				(type default)
			)
			(layer "F.Fab")
		)
		(fp_line
			(start -0.12065 0.3048)
			(end -0.67945 0.3048)
			(stroke
				(width 0.1)
				(type default)
			)
			(layer "F.Fab")
		)
		(fp_line
			(start -0.12065 0.2794)
			(end -0.12065 0.3048)
			(stroke
				(width 0.1)
				(type default)
			)
			(layer "F.Fab")
		)
		(fp_line
			(start -0.12065 -0.2794)
			(end 0.12065 -0.2794)
			(stroke
				(width 0.1)
				(type default)
			)
			(layer "F.Fab")
		)
		(fp_line
			(start -0.12065 -0.305054)
			(end -0.12065 -0.2794)
			(stroke
				(width 0.1)
				(type default)
			)
			(layer "F.Fab")
		)
		(fp_line
			(start -0.67945 0.3048)
			(end -0.67945 -0.305054)
			(stroke
				(width 0.1)
				(type default)
			)
			(layer "F.Fab")
		)
		(fp_line
			(start -0.67945 -0.305054)
			(end -0.12065 -0.305054)
			(stroke
				(width 0.1)
				(type default)
			)
			(layer "F.Fab")
		)
		(pad "1" smd circle
			(at -0.40005 0 180)
			(size 0 0)
			(layers "F.Cu" "F.Mask" "F.Paste")
			(net "PEX_P1V8_ADC_A0")
		)
		(pad "2" smd circle
			(at 0.40005 0 180)
			(size 0 0)
			(layers "F.Cu" "F.Mask" "F.Paste")
			(net "GND")
		)
	)
	(footprint ""
		(layer "F.Cu")
		(at 15.887446 -211.737956 180)
		(property "Reference" "U430"
			(at -4.162806 0.952246 0)
			(unlocked yes)
			(layer "F.SilkS")
			(effects
				(font
					(size 0.7874 0.5842)
					(thickness 0.1524)
				)
				(justify left)
			)
		)
		(property "Value" ""
			(at 0 0 180)
			(layer "F.Fab")
			(effects
				(font
					(size 1.27 1.27)
				)
			)
		)
		(duplicate_pad_numbers_are_jumpers no)
		(fp_line
			(start 1.525016 1.525016)
			(end 1.525016 1.3208)
			(stroke
				(width 0.1524)
				(type default)
			)
			(layer "F.SilkS")
		)
		(fp_line
			(start 1.525016 1.525016)
			(end -1.525016 1.525016)
			(stroke
				(width 0.1524)
				(type default)
			)
			(layer "F.SilkS")
		)
		(fp_line
			(start 1.525016 -1.3208)
			(end 1.525016 -1.525016)
			(stroke
				(width 0.1524)
				(type default)
			)
			(layer "F.SilkS")
		)
		(fp_line
			(start 1.525016 -1.525016)
			(end 0.9398 -1.525016)
			(stroke
				(width 0.1524)
				(type default)
			)
			(layer "F.SilkS")
		)
		(fp_line
			(start 1.525016 -1.525016)
			(end -1.525016 -1.525016)
			(stroke
				(width 0.1524)
				(type default)
			)
			(layer "F.SilkS")
		)
		(fp_line
			(start 0.9906 1.525016)
			(end 1.525016 1.525016)
			(stroke
				(width 0.1524)
				(type default)
			)
			(layer "F.SilkS")
		)
		(fp_line
			(start -0.8636 -1.525016)
			(end -1.525016 -1.525016)
			(stroke
				(width 0.1524)
				(type default)
			)
			(layer "F.SilkS")
		)
		(fp_line
			(start -1.525016 1.525016)
			(end -0.889 1.525016)
			(stroke
				(width 0.1524)
				(type default)
			)
			(layer "F.SilkS")
		)
		(fp_line
			(start -1.525016 1.3208)
			(end -1.525016 1.525016)
			(stroke
				(width 0.1524)
				(type default)
			)
			(layer "F.SilkS")
		)
		(fp_line
			(start -1.525016 -1.525016)
			(end -1.525016 -1.3208)
			(stroke
				(width 0.1524)
				(type default)
			)
			(layer "F.SilkS")
		)
		(fp_poly
			(pts
				(xy -2.234438 -1.001268) (xy -1.934464 -1.901444) (xy -2.534412 -1.901444)
			)
			(stroke
				(width 0)
				(type default)
			)
			(fill yes)
			(layer "F.SilkS")
		)
		(fp_line
			(start 1.525016 1.525016)
			(end -1.525016 1.525016)
			(stroke
				(width 0.1)
				(type default)
			)
			(layer "F.Fab")
		)
		(fp_line
			(start 1.525016 -1.525016)
			(end 1.525016 1.525016)
			(stroke
				(width 0.1)
				(type default)
			)
			(layer "F.Fab")
		)
		(fp_line
			(start -1.525016 1.525016)
			(end -1.525016 -1.525016)
			(stroke
				(width 0.1)
				(type default)
			)
			(layer "F.Fab")
		)
		(fp_line
			(start -1.525016 -1.525016)
			(end 1.525016 -1.525016)
			(stroke
				(width 0.1)
				(type default)
			)
			(layer "F.Fab")
		)
		(fp_poly
			(pts
				(xy -2.0701 -0.999998) (xy -2.977896 -1.302512) (xy -2.977896 -0.697484)
			)
			(stroke
				(width 0)
				(type default)
			)
			(fill yes)
			(layer "F.Fab")
		)
		(pad "1" smd rect
			(at -1.550162 -0.999998 90)
			(size 0.2794 0.9144)
			(layers "F.Cu" "F.Mask" "F.Paste")
			(net "P1V8_PLL0_PEX0")
		)
		(pad "2" smd rect
			(at -1.550162 -0.500126 90)
			(size 0.2794 0.9144)
			(layers "F.Cu" "F.Mask" "F.Paste")
			(net "P1V8_PLL0_PEX0")
		)
		(pad "3" smd rect
			(at -1.550162 0 90)
			(size 0.2794 0.9144)
			(layers "F.Cu" "F.Mask" "F.Paste")
			(net "P1V8_PLL0_PEX0")
		)
		(pad "4" smd rect
			(at -1.550162 0.500126 90)
			(size 0.2794 0.9144)
			(layers "F.Cu" "F.Mask" "F.Paste")
			(net "P1V8_PLL_PEX0_ADJ")
		)
		(pad "5" smd rect
			(at -1.550162 0.999998 270)
			(size 0.2794 0.9144)
			(layers "F.Cu" "F.Mask" "F.Paste")
			(net "PWRGD_PEX0_P1V8_PLL")
		)
		(pad "6" smd rect
			(at 1.550162 0.999998 270)
			(size 0.2794 0.9144)
			(layers "F.Cu" "F.Mask" "F.Paste")
			(net "PEX0_P1V8_PLL_EN")
		)
		(pad "7" smd rect
			(at 1.550162 0.500126 90)
			(size 0.2794 0.9144)
			(layers "F.Cu" "F.Mask" "F.Paste")
			(net "P3V3_AUX")
		)
		(pad "8" smd rect
			(at 1.550162 0 90)
			(size 0.2794 0.9144)
			(layers "F.Cu" "F.Mask" "F.Paste")
			(net "P3V3_AUX")
		)
		(pad "9" smd rect
			(at 1.550162 -0.500126 90)
			(size 0.2794 0.9144)
			(layers "F.Cu" "F.Mask" "F.Paste")
			(net "P3V3_AUX")
		)
		(pad "10" smd rect
			(at 1.550162 -0.999998 90)
			(size 0.2794 0.9144)
			(layers "F.Cu" "F.Mask" "F.Paste")
			(net "P5V_AUX")
		)
		(pad "TH" smd rect
			(at 0 0 180)
			(size 1.7526 2.667)
			(layers "F.Cu" "F.Mask" "F.Paste")
			(net "GND")
		)
		(zone
			(layer "F.Cu")
			(hatch none 0.5)
			(connect_pads
				(clearance 0)
			)
			(min_thickness 0.25)
			(keepout
				(tracks not_allowed)
				(vias allowed)
				(pads allowed)
				(copperpour not_allowed)
				(footprints allowed)
			)
			(placement
				(enabled no)
				(sheetname "")
			)
			(fill
				(thermal_gap 0.5)
				(thermal_bridge_width 0.5)
				(island_removal_mode 0)
			)
			(polygon
				(pts
					(xy 16.904208 -210.204558) (xy 16.904208 -213.252558) (xy 14.872208 -213.252558) (xy 14.872208 -210.204558)
					(xy 16.802608 -210.204558) (xy 16.802608 -210.331558) (xy 14.948408 -210.331558) (xy 14.948408 -213.150958)
					(xy 16.828008 -213.150958) (xy 16.828008 -210.204558)
				)
			)
		)
	)
	(footprint ""
		(layer "F.Cu")
		(at 215.784176 -369.000786 90)
		(property "Reference" "PC10"
			(at 0 0 90)
			(layer "F.SilkS")
			(hide yes)
			(effects
				(font
					(size 1.27 1.27)
				)
			)
		)
		(property "Value" ""
			(at 0 0 90)
			(layer "F.Fab")
			(effects
				(font
					(size 1.27 1.27)
				)
			)
		)
		(duplicate_pad_numbers_are_jumpers no)
		(fp_line
			(start 0.7874 -0.4064)
			(end 0.7874 0.4064)
			(stroke
				(width 0.1524)
				(type default)
			)
			(layer "F.SilkS")
		)
		(fp_line
			(start -0.7874 -0.4064)
			(end 0.7874 -0.4064)
			(stroke
				(width 0.1524)
				(type default)
			)
			(layer "F.SilkS")
		)
		(fp_line
			(start 0.7874 0.4064)
			(end -0.7874 0.4064)
			(stroke
				(width 0.1524)
				(type default)
			)
			(layer "F.SilkS")
		)
		(fp_line
			(start -0.7874 0.4064)
			(end -0.7874 -0.4064)
			(stroke
				(width 0.1524)
				(type default)
			)
			(layer "F.SilkS")
		)
		(fp_line
			(start -0.12065 -0.305054)
			(end -0.12065 -0.2794)
			(stroke
				(width 0.1)
				(type default)
			)
			(layer "F.Fab")
		)
		(fp_line
			(start -0.67945 -0.305054)
			(end -0.12065 -0.305054)
			(stroke
				(width 0.1)
				(type default)
			)
			(layer "F.Fab")
		)
		(fp_line
			(start 0.67945 -0.3048)
			(end 0.67945 0.3048)
			(stroke
				(width 0.1)
				(type default)
			)
			(layer "F.Fab")
		)
		(fp_line
			(start 0.12065 -0.3048)
			(end 0.67945 -0.3048)
			(stroke
				(width 0.1)
				(type default)
			)
			(layer "F.Fab")
		)
		(fp_line
			(start 0.12065 -0.2794)
			(end 0.12065 -0.3048)
			(stroke
				(width 0.1)
				(type default)
			)
			(layer "F.Fab")
		)
		(fp_line
			(start -0.12065 -0.2794)
			(end 0.12065 -0.2794)
			(stroke
				(width 0.1)
				(type default)
			)
			(layer "F.Fab")
		)
		(fp_line
			(start 0.120396 0.2794)
			(end -0.12065 0.2794)
			(stroke
				(width 0.1)
				(type default)
			)
			(layer "F.Fab")
		)
		(fp_line
			(start -0.12065 0.2794)
			(end -0.12065 0.3048)
			(stroke
				(width 0.1)
				(type default)
			)
			(layer "F.Fab")
		)
		(fp_line
			(start 0.67945 0.3048)
			(end 0.120396 0.3048)
			(stroke
				(width 0.1)
				(type default)
			)
			(layer "F.Fab")
		)
		(fp_line
			(start 0.120396 0.3048)
			(end 0.120396 0.2794)
			(stroke
				(width 0.1)
				(type default)
			)
			(layer "F.Fab")
		)
		(fp_line
			(start -0.12065 0.3048)
			(end -0.67945 0.3048)
			(stroke
				(width 0.1)
				(type default)
			)
			(layer "F.Fab")
		)
		(fp_line
			(start -0.67945 0.3048)
			(end -0.67945 -0.305054)
			(stroke
				(width 0.1)
				(type default)
			)
			(layer "F.Fab")
		)
		(pad "1" smd circle
			(at -0.40005 0 90)
			(size 0 0)
			(layers "F.Cu" "F.Mask" "F.Paste")
			(net "HSC_VDD_1")
		)
		(pad "2" smd circle
			(at 0.40005 0 90)
			(size 0 0)
			(layers "F.Cu" "F.Mask" "F.Paste")
			(net "AGND_HSC")
		)
	)
	(footprint ""
		(layer "F.Cu")
		(at 460.611982 -110.515654)
		(property "Reference" "PC836"
			(at 0 0 0)
			(layer "F.SilkS")
			(hide yes)
			(effects
				(font
					(size 1.27 1.27)
				)
			)
		)
		(property "Value" ""
			(at 0 0 0)
			(layer "F.Fab")
			(effects
				(font
					(size 1.27 1.27)
				)
			)
		)
		(duplicate_pad_numbers_are_jumpers no)
		(fp_line
			(start -0.7874 -0.4064)
			(end 0.7874 -0.4064)
			(stroke
				(width 0.1524)
				(type default)
			)
			(layer "F.SilkS")
		)
		(fp_line
			(start -0.7874 0.4064)
			(end -0.7874 -0.4064)
			(stroke
				(width 0.1524)
				(type default)
			)
			(layer "F.SilkS")
		)
		(fp_line
			(start 0.7874 -0.4064)
			(end 0.7874 0.4064)
			(stroke
				(width 0.1524)
				(type default)
			)
			(layer "F.SilkS")
		)
		(fp_line
			(start 0.7874 0.4064)
			(end -0.7874 0.4064)
			(stroke
				(width 0.1524)
				(type default)
			)
			(layer "F.SilkS")
		)
		(fp_line
			(start -0.67945 -0.305054)
			(end -0.12065 -0.305054)
			(stroke
				(width 0.1)
				(type default)
			)
			(layer "F.Fab")
		)
		(fp_line
			(start -0.67945 0.3048)
			(end -0.67945 -0.305054)
			(stroke
				(width 0.1)
				(type default)
			)
			(layer "F.Fab")
		)
		(fp_line
			(start -0.12065 -0.305054)
			(end -0.12065 -0.2794)
			(stroke
				(width 0.1)
				(type default)
			)
			(layer "F.Fab")
		)
		(fp_line
			(start -0.12065 -0.2794)
			(end 0.12065 -0.2794)
			(stroke
				(width 0.1)
				(type default)
			)
			(layer "F.Fab")
		)
		(fp_line
			(start -0.12065 0.2794)
			(end -0.12065 0.3048)
			(stroke
				(width 0.1)
				(type default)
			)
			(layer "F.Fab")
		)
		(fp_line
			(start -0.12065 0.3048)
			(end -0.67945 0.3048)
			(stroke
				(width 0.1)
				(type default)
			)
			(layer "F.Fab")
		)
		(fp_line
			(start 0.120396 0.2794)
			(end -0.12065 0.2794)
			(stroke
				(width 0.1)
				(type default)
			)
			(layer "F.Fab")
		)
		(fp_line
			(start 0.120396 0.3048)
			(end 0.120396 0.2794)
			(stroke
				(width 0.1)
				(type default)
			)
			(layer "F.Fab")
		)
		(fp_line
			(start 0.12065 -0.3048)
			(end 0.67945 -0.3048)
			(stroke
				(width 0.1)
				(type default)
			)
			(layer "F.Fab")
		)
		(fp_line
			(start 0.12065 -0.2794)
			(end 0.12065 -0.3048)
			(stroke
				(width 0.1)
				(type default)
			)
			(layer "F.Fab")
		)
		(fp_line
			(start 0.67945 -0.3048)
			(end 0.67945 0.3048)
			(stroke
				(width 0.1)
				(type default)
			)
			(layer "F.Fab")
		)
		(fp_line
			(start 0.67945 0.3048)
			(end 0.120396 0.3048)
			(stroke
				(width 0.1)
				(type default)
			)
			(layer "F.Fab")
		)
		(pad "1" smd circle
			(at -0.40005 0)
			(size 0 0)
			(layers "F.Cu" "F.Mask" "F.Paste")
			(net "P12V_NIC7_CO_TIMER")
		)
		(pad "2" smd circle
			(at 0.40005 0)
			(size 0 0)
			(layers "F.Cu" "F.Mask" "F.Paste")
			(net "GND")
		)
	)
)
